# S9S_MB_2U (Grand Teton) — schematic netlist excerpt (pin names and nets, part order shuffled) for the footprints in the layout excerpt that follows; sources: Cadence DE-HDL packaged netlist, KiCad conversion of 03242023_DA0F0TMBIJ0_F0T_Motherboard_J_brd_V01_OCP.brd

R3215  Q_RES  0 5% EMPTY  pkg 0402LF  page 160 : A = NCSI_BMC_TXD1_R1 ; B = RMII_BMC_OCP_TXD_1
PR227  Q_RES  2.2 1% CHIP  pkg 0402LF  page 289 : A = PVCCFA_EHV_FIVRA_CPU1_PVCC2 ; B = PVCCFA_EHV_FIVRA_CPU1_VDD2

(kicad_pcb
	(version 20260206)
	(generator "pcbnew")
	(generator_version "10.0")
	(general
		(thickness 1.6)
		(legacy_teardrops no)
	)
	(paper "A4")
	(title_block
		(title "03242023_DA0F0TMBIJ0_F0T_Motherboard_J_brd_V01_OCP.brd")
		(comment 1 "Grand Teton / footprints 4570-4571 of 6105")
	)
	(layers
		(0 "F.Cu" signal "TOP")
		(4 "In1.Cu" signal "GND")
		(6 "In2.Cu" signal "IN1")
		(8 "In3.Cu" signal "GND1")
		(10 "In4.Cu" signal "IN2")
		(12 "In5.Cu" signal "GND2")
		(14 "In6.Cu" signal "IN3")
		(16 "In7.Cu" signal "GND3")
		(18 "In8.Cu" signal "VCC")
		(20 "In9.Cu" signal "VCC1")
		(22 "In10.Cu" signal "GND4")
		(24 "In11.Cu" signal "IN4")
		(26 "In12.Cu" signal "GND5")
		(28 "In13.Cu" signal "IN5")
		(30 "In14.Cu" signal "GND6")
		(32 "In15.Cu" signal "IN6")
		(34 "In16.Cu" signal "GND7")
		(2 "B.Cu" signal "BOTTOM")
		(9 "F.Adhes" user "F.Adhesive")
		(11 "B.Adhes" user "B.Adhesive")
		(13 "F.Paste" user "Package Geometry/Pastemask Top")
		(15 "B.Paste" user "Package Geometry/Pastemask Bottom")
		(5 "F.SilkS" user "Ref Des/Silkscreen Top")
		(7 "B.SilkS" user "Ref Des/Silkscreen Bottom")
		(1 "F.Mask" user "Board Geometry/Soldermask Top")
		(3 "B.Mask" user "Board Geometry/Soldermask Bottom")
		(17 "Dwgs.User" user "User.Drawings")
		(19 "Cmts.User" user "User.Comments")
		(21 "Eco1.User" user "User.Eco1")
		(23 "Eco2.User" user "User.Eco2")
		(25 "Edge.Cuts" user "Board Geometry/Outline")
		(27 "Margin" user)
		(31 "F.CrtYd" user "Package Geometry/Place Bound Top")
		(29 "B.CrtYd" user "Package Geometry/Place Bound Bottom")
		(35 "F.Fab" user "Ref Des/Assembly Top")
		(33 "B.Fab" user "Ref Des/Assembly Bottom")
	)
	(footprint ""
		(layer "B.Cu")
		(at 48.344328 -354.558854 -90)
		(property "Reference" "PR227"
			(at 0 0 90)
			(layer "B.SilkS")
			(hide yes)
			(effects
				(font
					(size 1.27 1.27)
				)
				(justify mirror)
			)
		)
		(property "Value" ""
			(at 0 0 90)
			(layer "B.Fab")
			(effects
				(font
					(size 1.27 1.27)
				)
				(justify mirror)
			)
		)
		(duplicate_pad_numbers_are_jumpers no)
		(fp_line
			(start -0.7874 0.4064)
			(end 0.7874 0.4064)
			(stroke
				(width 0.1524)
				(type default)
			)
			(layer "B.SilkS")
		)
		(fp_line
			(start 0.7874 0.4064)
			(end 0.7874 -0.4064)
			(stroke
				(width 0.1524)
				(type default)
			)
			(layer "B.SilkS")
		)
		(fp_line
			(start -0.7874 -0.4064)
			(end -0.7874 0.4064)
			(stroke
				(width 0.1524)
				(type default)
			)
			(layer "B.SilkS")
		)
		(fp_line
			(start 0.7874 -0.4064)
			(end -0.7874 -0.4064)
			(stroke
				(width 0.1524)
				(type default)
			)
			(layer "B.SilkS")
		)
		(fp_line
			(start -0.67945 0.3048)
			(end -0.120396 0.3048)
			(stroke
				(width 0.1)
				(type default)
			)
			(layer "B.Fab")
		)
		(fp_line
			(start -0.120396 0.3048)
			(end -0.120396 0.2794)
			(stroke
				(width 0.1)
				(type default)
			)
			(layer "B.Fab")
		)
		(fp_line
			(start 0.12065 0.3048)
			(end 0.67945 0.3048)
			(stroke
				(width 0.1)
				(type default)
			)
			(layer "B.Fab")
		)
		(fp_line
			(start 0.67945 0.3048)
			(end 0.67945 -0.305054)
			(stroke
				(width 0.1)
				(type default)
			)
			(layer "B.Fab")
		)
		(fp_line
			(start -0.120396 0.2794)
			(end 0.12065 0.2794)
			(stroke
				(width 0.1)
				(type default)
			)
			(layer "B.Fab")
		)
		(fp_line
			(start 0.12065 0.2794)
			(end 0.12065 0.3048)
			(stroke
				(width 0.1)
				(type default)
			)
			(layer "B.Fab")
		)
		(fp_line
			(start -0.12065 -0.2794)
			(end -0.12065 -0.3048)
			(stroke
				(width 0.1)
				(type default)
			)
			(layer "B.Fab")
		)
		(fp_line
			(start 0.12065 -0.2794)
			(end -0.12065 -0.2794)
			(stroke
				(width 0.1)
				(type default)
			)
			(layer "B.Fab")
		)
		(fp_line
			(start -0.67945 -0.3048)
			(end -0.67945 0.3048)
			(stroke
				(width 0.1)
				(type default)
			)
			(layer "B.Fab")
		)
		(fp_line
			(start -0.12065 -0.3048)
			(end -0.67945 -0.3048)
			(stroke
				(width 0.1)
				(type default)
			)
			(layer "B.Fab")
		)
		(fp_line
			(start 0.12065 -0.305054)
			(end 0.12065 -0.2794)
			(stroke
				(width 0.1)
				(type default)
			)
			(layer "B.Fab")
		)
		(fp_line
			(start 0.67945 -0.305054)
			(end 0.12065 -0.305054)
			(stroke
				(width 0.1)
				(type default)
			)
			(layer "B.Fab")
		)
		(pad "1" smd circle
			(at 0.40005 0 90)
			(size 0 0)
			(layers "B.Cu" "B.Mask" "B.Paste")
			(net "PVCCFA_EHV_FIVRA_CPU1_PVCC2")
		)
		(pad "2" smd circle
			(at -0.40005 0 90)
			(size 0 0)
			(layers "B.Cu" "B.Mask" "B.Paste")
			(net "PVCCFA_EHV_FIVRA_CPU1_VDD2")
		)
	)
	(footprint ""
		(layer "B.Cu")
		(at 206.176372 -72.214994 180)
		(property "Reference" "R3215"
			(at 0 0 0)
			(layer "B.SilkS")
			(hide yes)
			(effects
				(font
					(size 1.27 1.27)
				)
				(justify mirror)
			)
		)
		(property "Value" ""
			(at 0 0 0)
			(layer "B.Fab")
			(effects
				(font
					(size 1.27 1.27)
				)
				(justify mirror)
			)
		)
		(duplicate_pad_numbers_are_jumpers no)
		(fp_line
			(start 0.7874 0.4064)
			(end 0.7874 -0.4064)
			(stroke
				(width 0.1524)
				(type default)
			)
			(layer "B.SilkS")
		)
		(fp_line
			(start 0.7874 -0.4064)
			(end -0.7874 -0.4064)
			(stroke
				(width 0.1524)
				(type default)
			)
			(layer "B.SilkS")
		)
		(fp_line
			(start -0.7874 0.4064)
			(end 0.7874 0.4064)
			(stroke
				(width 0.1524)
				(type default)
			)
			(layer "B.SilkS")
		)
		(fp_line
			(start -0.7874 -0.4064)
			(end -0.7874 0.4064)
			(stroke
				(width 0.1524)
				(type default)
			)
			(layer "B.SilkS")
		)
		(fp_line
			(start 0.67945 0.3048)
			(end 0.67945 -0.305054)
			(stroke
				(width 0.1)
				(type default)
			)
			(layer "B.Fab")
		)
		(fp_line
			(start 0.67945 -0.305054)
			(end 0.12065 -0.305054)
			(stroke
				(width 0.1)
				(type default)
			)
			(layer "B.Fab")
		)
		(fp_line
			(start 0.12065 0.3048)
			(end 0.67945 0.3048)
			(stroke
				(width 0.1)
				(type default)
			)
			(layer "B.Fab")
		)
		(fp_line
			(start 0.12065 0.2794)
			(end 0.12065 0.3048)
			(stroke
				(width 0.1)
				(type default)
			)
			(layer "B.Fab")
		)
		(fp_line
			(start 0.12065 -0.2794)
			(end -0.12065 -0.2794)
			(stroke
				(width 0.1)
				(type default)
			)
			(layer "B.Fab")
		)
		(fp_line
			(start 0.12065 -0.305054)
			(end 0.12065 -0.2794)
			(stroke
				(width 0.1)
				(type default)
			)
			(layer "B.Fab")
		)
		(fp_line
			(start -0.120396 0.3048)
			(end -0.120396 0.2794)
			(stroke
				(width 0.1)
				(type default)
			)
			(layer "B.Fab")
		)
		(fp_line
			(start -0.120396 0.2794)
			(end 0.12065 0.2794)
			(stroke
				(width 0.1)
				(type default)
			)
			(layer "B.Fab")
		)
		(fp_line
			(start -0.12065 -0.2794)
			(end -0.12065 -0.3048)
			(stroke
				(width 0.1)
				(type default)
			)
			(layer "B.Fab")
		)
		(fp_line
			(start -0.12065 -0.3048)
			(end -0.67945 -0.3048)
			(stroke
				(width 0.1)
				(type default)
			)
			(layer "B.Fab")
		)
		(fp_line
			(start -0.67945 0.3048)
			(end -0.120396 0.3048)
			(stroke
				(width 0.1)
				(type default)
			)
			(layer "B.Fab")
		)
		(fp_line
			(start -0.67945 -0.3048)
			(end -0.67945 0.3048)
			(stroke
				(width 0.1)
				(type default)
			)
			(layer "B.Fab")
		)
		(pad "1" smd circle
			(at 0.40005 0)
			(size 0 0)
			(layers "B.Cu" "B.Mask" "B.Paste")
			(net "NCSI_BMC_TXD1_R1")
		)
		(pad "2" smd circle
			(at -0.40005 0)
			(size 0 0)
			(layers "B.Cu" "B.Mask" "B.Paste")
			(net "RMII_BMC_OCP_TXD_1")
		)
	)
)
